FILE_TYPE = CONNECTIVITY;
{Allegro Design Entry HDL 17.2-2016 S081 (4005846) 1/11/2022}
"PAGE_NUMBER" = 117;
0"NC";
END.
